# ZAIUS-LBB-EVT2-X01-BOM-X03-20161116.xls — Changelist (bom)
| BOM Change List Date:Wed Aug 31 10:55:17 GMT+08:00 2016 |  |  |  |  |  |  |  |  |  |
| New BOM file : C:\<user>\ZAIUS-LBB-EVT-HW-EBOM-X00_20160829-X03_20160831.xls |  |  |  |  |  |  |  |  |  |
| Old BOM file : C:\<user>\ZAIUS-LBB-EVT-HW-EBOM-X00_20160824-1100-X02_20160824.xls |  |  |  |  |  |  |  |  |  |
| ##### Add Parts |  |  |  |  |  |  |  |  |  |
| Item | Location | Qty | Foxconn P/N | Part Description | Manufacturer Full Name | Manufacturer P/N | RoHS | Sheet |  |
| ##### Remove Parts |  |  |  |  |  |  |  |  |  |
| Item | Location | Qty | Foxconn P/N | Part Description | Manufacturer Full Name | Manufacturer P/N | RoHS | Sheet |  |
| ##### Change Parts |  |  |  |  |  |  |  |  |  |
| Item | Location | Qty | Foxconn P/N | Part Description | Manufacturer Full Name | Manufacturer P/N | RoHS | Sheet | Remark |
| 1 | C29,C33 | 2 | TBD-C1812C105K1RACTU | CAP,1uF,+/-10%,X7R,100V,G,SMD1812 | KEMET | C1812C105K1RACTU | Y | PWA BOM | In New BOM |
|  | C29,C33 | 2 | 62011DA00-015-G | CAP,1uF,+/-10%,X7R,100V,G,SMD1206 | MURATA ELEC. NORTH AMERICA | GRM31CR72A105K | Y | PWA BOM | In Old BOM |
|  |  |  | 62011DA00-026-G | CAP,1uF,+/-10%,X7R,100V,G,SMD1206 | SAMSUNG SEMICONDUCTOR | CL31B105KCHNNNE |  | PWA BOM | In Old BOM |
|  |  |  | 62011DA00-023-G | CAP,1uF,+/-10%,X7R,100V,G,SMD1206 | TAIYO ELECTRIC IND.CO.LTD | HMK316B7105KL-T |  | PWA BOM | In Old BOM |
| 2 | C30,C31,C32,C34,C35,C36 | 6 | TBD-C1812C225K1RACTU | CAP,2.2uF,+/-10%,X7R,100V,G,SMD1812 | KEMET | C1812C225K1RACTU |  | PWA BOM | In New BOM |
|  | C30,C31,C32,C34,C35,C36 | 6 | 62011J601-015-G | CAP,2.2uF,+/-10%,X7R,100V,G,SMD1210 | MURATA ELEC. NORTH AMERICA | GRM32ER72A225K |  | PWA BOM | In Old BOM |
|  |  |  | 62011J600-026-G | CAP,2.2uF,+/-10%,X7R,100V,G,SMD1210 | SAMSUNG SEMICONDUCTOR | CL32B225KCJSNNE |  | PWA BOM | In Old BOM |
|  |  |  | 62011J600-023-G | CAP,2.2uF,+/-10%,X7R,100V,G,SMD1210 | TAIYO ELECTRIC IND.CO.LTD | HMK325B7225KN-T |  | PWA BOM | In Old BOM |
| ##### Change Revision |  |  |  |  |  |  |  |  |  |
| Sheet | REV OF BOM | CUSTOMER | CUSTOMER P/N | PWA PN | PWA DESCRIPTION | PWA REV | DATE | Remark |  |
| PWA BOM | X03 | DELL |  | 10035WH00-600-G | Peripheral Board,G,Zaius-LBB | X00 | 8/31/16 | In New BOM |  |
| PWA BOM | X02 | DELL |  | 10035WH00-600-G | Peripheral Board,G,Zaius-LBB | X00 | 8/24/16 | In Old BOM |  |
| OOOOOOOOOOOOOOOOOOOOOOOOOOOOOOOOOOOOOOOOOOOOOOOOOOOOOOOOOOOOOOOOOOOOOOOOOOOOOOOOOOOOOOOOOO | OOOOOOOOOOOOOOOOOOOOOOOOOOOOOOOOOOOOOOOOOOOOOOOOOOOOOOOOOOOOOOOOOOOOOOOOOOOOOOOOOOOOOOOOOO | OOOOOOOOOOOOOOOOOOOOOOOOOOOOOOOOOOOOOOOOOOOOOOOOOOOOOOOOOOOOOOOOOOOOOOOOOOOOOOOOOOOOOOOOOO | OOOOOOOOOOOOOOOOOOOOOOOOOOOOOOOOOOOOOOOOOOOOOOOOOOOOOOOOOOOOOOOOOOOOOOOOOOOOOOOOOOOOOOOOOO | OOOOOOOOOOOOOOOOOOOOOOOOOOOOOOOOOOOOOOOOOOOOOOOOOOOOOOOOOOOOOOOOOOOOOOOOOOOOOOOOOOOOOOOOOO | OOOOOOOOOOOOOOOOOOOOOOOOOOOOOOOOOOOOOOOOOOOOOOOOOOOOOOOOOOOOOOOOOOOOOOOOOOOOOOOOOOOOOOOOOO | OOOOOOOOOOOOOOOOOOOOOOOOOOOOOOOOOOOOOOOOOOOOOOOOOOOOOOOOOOOOOOOOOOOOOOOOOOOOOOOOOOOOOOOOOO | OOOOOOOOOOOOOOOOOOOOOOOOOOOOOOOOOOOOOOOOOOOOOOOOOOOOOOOOOOOOOOOOOOOOOOOOOOOOOOOOOOOOOOOOOO | OOOOOOOOOOOOOOOOOOOOOOOOOOOOOOOOOOOOOOOOOOOOOOOOOOOOOOOOOOOOOOOOOOOOOOOOOOOOOOOOOOOOOOOOOO | OOOOOOOOOOOOOOOOOOOOOOOOOOOOOOOOOOOOOOOOOOOOOOOOOOOOOOOOOOOOOOOOOOOOOOOOOOOOOOOOOOOOOOOOOO |
| Second Source Change |  |  |  |  |  |  |  |  |  |
| Item | Location | Change Type | Foxconn P/N | Part Description | Manufacturer Full Name | Manufacturer P/N | RoHS | Sheet |  |
| OOOOOOOOOOOOOOOOOOOOOOOOOOOOOOOOOOOOOOOOOOOOOOOOOOOOOOOOOOOOOOOOOOOOOOOOOOOOOOOOOOOOOOOOOO | OOOOOOOOOOOOOOOOOOOOOOOOOOOOOOOOOOOOOOOOOOOOOOOOOOOOOOOOOOOOOOOOOOOOOOOOOOOOOOOOOOOOOOOOOO | OOOOOOOOOOOOOOOOOOOOOOOOOOOOOOOOOOOOOOOOOOOOOOOOOOOOOOOOOOOOOOOOOOOOOOOOOOOOOOOOOOOOOOOOOO | OOOOOOOOOOOOOOOOOOOOOOOOOOOOOOOOOOOOOOOOOOOOOOOOOOOOOOOOOOOOOOOOOOOOOOOOOOOOOOOOOOOOOOOOOO | OOOOOOOOOOOOOOOOOOOOOOOOOOOOOOOOOOOOOOOOOOOOOOOOOOOOOOOOOOOOOOOOOOOOOOOOOOOOOOOOOOOOOOOOOO | OOOOOOOOOOOOOOOOOOOOOOOOOOOOOOOOOOOOOOOOOOOOOOOOOOOOOOOOOOOOOOOOOOOOOOOOOOOOOOOOOOOOOOOOOO | OOOOOOOOOOOOOOOOOOOOOOOOOOOOOOOOOOOOOOOOOOOOOOOOOOOOOOOOOOOOOOOOOOOOOOOOOOOOOOOOOOOOOOOOOO | OOOOOOOOOOOOOOOOOOOOOOOOOOOOOOOOOOOOOOOOOOOOOOOOOOOOOOOOOOOOOOOOOOOOOOOOOOOOOOOOOOOOOOOOOO | OOOOOOOOOOOOOOOOOOOOOOOOOOOOOOOOOOOOOOOOOOOOOOOOOOOOOOOOOOOOOOOOOOOOOOOOOOOOOOOOOOOOOOOOOO | OOOOOOOOOOOOOOOOOOOOOOOOOOOOOOOOOOOOOOOOOOOOOOOOOOOOOOOOOOOOOOOOOOOOOOOOOOOOOOOOOOOOOOOOOO |
| Master Materials Change |  |  |  |  |  |  |  |  |  |
| Item | Foxconn P/N | Orig._Usage | New_Usage | Part Description | Manufacturer Full Name | Manufacturer P/N | RoHS | Location | Sheet |
| 1 | TBD-C1812C105K1RACTU | 0 | 2 | CAP,1uF,+/-10%,X7R,100V,G,SMD1812 | KEMET | C1812C105K1RACTU | Y | (+)C29,C33 | PWA BOM |
| 2 | TBD-C1812C225K1RACTU | 0 | 6 | CAP,2.2uF,+/-10%,X7R,100V,G,SMD1812 | KEMET | C1812C225K1RACTU |  | (+)C30,C31,C32,C34,C35,C36 | PWA BOM |
| 3 | 62011DA00-015-G | 2 | 0 | CAP,1uF,+/-10%,X7R,100V,G,SMD1206 | MURATA ELEC. NORTH AMERICA | GRM31CR72A105K | Y | (-)C29,C33 | PWA BOM |
|  | 62011DA00-026-G |  |  | CAP,1uF,+/-10%,X7R,100V,G,SMD1206 | SAMSUNG SEMICONDUCTOR | CL31B105KCHNNNE |  |  | PWA BOM |
|  | 62011DA00-023-G |  |  | CAP,1uF,+/-10%,X7R,100V,G,SMD1206 | TAIYO ELECTRIC IND.CO.LTD | HMK316B7105KL-T |  |  | PWA BOM |
| 4 | 62011J601-015-G | 6 | 0 | CAP,2.2uF,+/-10%,X7R,100V,G,SMD1210 | MURATA ELEC. NORTH AMERICA | GRM32ER72A225K |  | (-)C30,C31,C32,C34,C35,C36 | PWA BOM |
|  | 62011J600-026-G |  |  | CAP,2.2uF,+/-10%,X7R,100V,G,SMD1210 | SAMSUNG SEMICONDUCTOR | CL32B225KCJSNNE |  |  | PWA BOM |
|  | 62011J600-023-G |  |  | CAP,2.2uF,+/-10%,X7R,100V,G,SMD1210 | TAIYO ELECTRIC IND.CO.LTD | HMK325B7225KN-T |  |  | PWA BOM |
| OOOOOOOOOOOOOOOOOOOOOOOOOOOOOOOOOOOOOOOOOOOOOOOOOOOOOOOOOOOOOOOOOOOOOOOOOOOOOOOOOOOOOOOOOO | OOOOOOOOOOOOOOOOOOOOOOOOOOOOOOOOOOOOOOOOOOOOOOOOOOOOOOOOOOOOOOOOOOOOOOOOOOOOOOOOOOOOOOOOOO | OOOOOOOOOOOOOOOOOOOOOOOOOOOOOOOOOOOOOOOOOOOOOOOOOOOOOOOOOOOOOOOOOOOOOOOOOOOOOOOOOOOOOOOOOO | OOOOOOOOOOOOOOOOOOOOOOOOOOOOOOOOOOOOOOOOOOOOOOOOOOOOOOOOOOOOOOOOOOOOOOOOOOOOOOOOOOOOOOOOOO | OOOOOOOOOOOOOOOOOOOOOOOOOOOOOOOOOOOOOOOOOOOOOOOOOOOOOOOOOOOOOOOOOOOOOOOOOOOOOOOOOOOOOOOOOO | OOOOOOOOOOOOOOOOOOOOOOOOOOOOOOOOOOOOOOOOOOOOOOOOOOOOOOOOOOOOOOOOOOOOOOOOOOOOOOOOOOOOOOOOOO | OOOOOOOOOOOOOOOOOOOOOOOOOOOOOOOOOOOOOOOOOOOOOOOOOOOOOOOOOOOOOOOOOOOOOOOOOOOOOOOOOOOOOOOOOO | OOOOOOOOOOOOOOOOOOOOOOOOOOOOOOOOOOOOOOOOOOOOOOOOOOOOOOOOOOOOOOOOOOOOOOOOOOOOOOOOOOOOOOOOOO | OOOOOOOOOOOOOOOOOOOOOOOOOOOOOOOOOOOOOOOOOOOOOOOOOOOOOOOOOOOOOOOOOOOOOOOOOOOOOOOOOOOOOOOOOO |  |
| TLA Parts Change |  |  |  |  |  |  |  |  |  |
| Item | Foxconn P/N | Qty | Part Description | Manufacturer Full Name | Manufacturer P/N | RoHS | Location | Remark |  |
| 1 | 7J-004-938 | 1 | L6 LABEL ( 12.7*11.1mm) | FOXCONN / EPD1 | 7J-004-938 | G |  | In New BOM |  |
| 2 | 7J-004-1582 | 2 | Label 1.25" (31.75mm) x 0.5"(6.35mm) | FOXCONN / EPD1 | 7J-004-1582 | G |  | In New BOM |  |
| 3 | 7J-004-940 | 1 | L6 LABEL ( 25.4*12.7mm) | FOXCONN / EPD1 | 7J-004-940 | G |  | In Old BOM |  |
| BOM Change List Date:Fri Sep 02 10:43:19 GMT+08:00 2016 |  |  |  |  |  |  |  |  |  |
| New BOM file : C:\<user>\ZAIUS-LBB-EVT-HW-EBOM-X00_20160829-X04_20160902.xls |  |  |  |  |  |  |  |  |  |
| Old BOM file : C:\<user>\ZAIUS-LBB-EVT-HW-EBOM-X00_20160829-X03_20160831.xls |  |  |  |  |  |  |  |  |  |
| ##### Add Parts |  |  |  |  |  |  |  |  |  |
| Item | Location | Qty | Foxconn P/N | Part Description | Manufacturer Full Name | Manufacturer P/N | RoHS | Sheet |  |
| ##### Remove Parts |  |  |  |  |  |  |  |  |  |
| Item | Location | Qty | Foxconn P/N | Part Description | Manufacturer Full Name | Manufacturer P/N | RoHS | Sheet |  |
| ##### Change Parts |  |  |  |  |  |  |  |  |  |
| Item | Location | Qty | Foxconn P/N | Part Description | Manufacturer Full Name | Manufacturer P/N | RoHS | Sheet | Remark |
| 1 | J6 | 1 | 3406AGU00-74S-G | CONN,Header,Power,R/A,Bla,14.99mm,G,DIP-6 | ANDERSON POWER PRODUCT | SBS75GPRBLK-BK |  | PWA BOM | In New BOM |
|  | J6 | 1 | TBD-SBS75GPRBLK-BK | SBS75 Power connector | ANDERSON POWER PRODUCT | SBS75GPRBLK-BK |  | PWA BOM | In Old BOM |
| ##### Change Revision |  |  |  |  |  |  |  |  |  |
| Sheet | REV OF BOM | CUSTOMER | CUSTOMER P/N | PWA PN | PWA DESCRIPTION | PWA REV | DATE | Remark |  |
| OOOOOOOOOOOOOOOOOOOOOOOOOOOOOOOOOOOOOOOOOOOOOOOOOOOOOOOOOOOOOOOOOOOOOOOOOOOOOOOOOOOOOOOOOO | OOOOOOOOOOOOOOOOOOOOOOOOOOOOOOOOOOOOOOOOOOOOOOOOOOOOOOOOOOOOOOOOOOOOOOOOOOOOOOOOOOOOOOOOOO | OOOOOOOOOOOOOOOOOOOOOOOOOOOOOOOOOOOOOOOOOOOOOOOOOOOOOOOOOOOOOOOOOOOOOOOOOOOOOOOOOOOOOOOOOO | OOOOOOOOOOOOOOOOOOOOOOOOOOOOOOOOOOOOOOOOOOOOOOOOOOOOOOOOOOOOOOOOOOOOOOOOOOOOOOOOOOOOOOOOOO | OOOOOOOOOOOOOOOOOOOOOOOOOOOOOOOOOOOOOOOOOOOOOOOOOOOOOOOOOOOOOOOOOOOOOOOOOOOOOOOOOOOOOOOOOO | OOOOOOOOOOOOOOOOOOOOOOOOOOOOOOOOOOOOOOOOOOOOOOOOOOOOOOOOOOOOOOOOOOOOOOOOOOOOOOOOOOOOOOOOOO | OOOOOOOOOOOOOOOOOOOOOOOOOOOOOOOOOOOOOOOOOOOOOOOOOOOOOOOOOOOOOOOOOOOOOOOOOOOOOOOOOOOOOOOOOO | OOOOOOOOOOOOOOOOOOOOOOOOOOOOOOOOOOOOOOOOOOOOOOOOOOOOOOOOOOOOOOOOOOOOOOOOOOOOOOOOOOOOOOOOOO | OOOOOOOOOOOOOOOOOOOOOOOOOOOOOOOOOOOOOOOOOOOOOOOOOOOOOOOOOOOOOOOOOOOOOOOOOOOOOOOOOOOOOOOOOO | OOOOOOOOOOOOOOOOOOOOOOOOOOOOOOOOOOOOOOOOOOOOOOOOOOOOOOOOOOOOOOOOOOOOOOOOOOOOOOOOOOOOOOOOOO |
| Second Source Change |  |  |  |  |  |  |  |  |  |
| Item | Location | Change Type | Foxconn P/N | Part Description | Manufacturer Full Name | Manufacturer P/N | RoHS | Sheet |  |
| OOOOOOOOOOOOOOOOOOOOOOOOOOOOOOOOOOOOOOOOOOOOOOOOOOOOOOOOOOOOOOOOOOOOOOOOOOOOOOOOOOOOOOOOOO | OOOOOOOOOOOOOOOOOOOOOOOOOOOOOOOOOOOOOOOOOOOOOOOOOOOOOOOOOOOOOOOOOOOOOOOOOOOOOOOOOOOOOOOOOO | OOOOOOOOOOOOOOOOOOOOOOOOOOOOOOOOOOOOOOOOOOOOOOOOOOOOOOOOOOOOOOOOOOOOOOOOOOOOOOOOOOOOOOOOOO | OOOOOOOOOOOOOOOOOOOOOOOOOOOOOOOOOOOOOOOOOOOOOOOOOOOOOOOOOOOOOOOOOOOOOOOOOOOOOOOOOOOOOOOOOO | OOOOOOOOOOOOOOOOOOOOOOOOOOOOOOOOOOOOOOOOOOOOOOOOOOOOOOOOOOOOOOOOOOOOOOOOOOOOOOOOOOOOOOOOOO | OOOOOOOOOOOOOOOOOOOOOOOOOOOOOOOOOOOOOOOOOOOOOOOOOOOOOOOOOOOOOOOOOOOOOOOOOOOOOOOOOOOOOOOOOO | OOOOOOOOOOOOOOOOOOOOOOOOOOOOOOOOOOOOOOOOOOOOOOOOOOOOOOOOOOOOOOOOOOOOOOOOOOOOOOOOOOOOOOOOOO | OOOOOOOOOOOOOOOOOOOOOOOOOOOOOOOOOOOOOOOOOOOOOOOOOOOOOOOOOOOOOOOOOOOOOOOOOOOOOOOOOOOOOOOOOO | OOOOOOOOOOOOOOOOOOOOOOOOOOOOOOOOOOOOOOOOOOOOOOOOOOOOOOOOOOOOOOOOOOOOOOOOOOOOOOOOOOOOOOOOOO | OOOOOOOOOOOOOOOOOOOOOOOOOOOOOOOOOOOOOOOOOOOOOOOOOOOOOOOOOOOOOOOOOOOOOOOOOOOOOOOOOOOOOOOOOO |
| Master Materials Change |  |  |  |  |  |  |  |  |  |
| Item | Foxconn P/N | Orig._Usage | New_Usage | Part Description | Manufacturer Full Name | Manufacturer P/N | RoHS | Location | Sheet |
| 1 | 3406AGU00-74S-G | 0 | 1 | CONN,Header,Power,R/A,Bla,14.99mm,G,DIP-6 | ANDERSON POWER PRODUCT | SBS75GPRBLK-BK |  | (+)J6 | PWA BOM |
| 2 | TBD-SBS75GPRBLK-BK | 1 | 0 | SBS75 Power connector | ANDERSON POWER PRODUCT | SBS75GPRBLK-BK |  | (-)J6 | PWA BOM |
| OOOOOOOOOOOOOOOOOOOOOOOOOOOOOOOOOOOOOOOOOOOOOOOOOOOOOOOOOOOOOOOOOOOOOOOOOOOOOOOOOOOOOOOOOO | OOOOOOOOOOOOOOOOOOOOOOOOOOOOOOOOOOOOOOOOOOOOOOOOOOOOOOOOOOOOOOOOOOOOOOOOOOOOOOOOOOOOOOOOOO | OOOOOOOOOOOOOOOOOOOOOOOOOOOOOOOOOOOOOOOOOOOOOOOOOOOOOOOOOOOOOOOOOOOOOOOOOOOOOOOOOOOOOOOOOO | OOOOOOOOOOOOOOOOOOOOOOOOOOOOOOOOOOOOOOOOOOOOOOOOOOOOOOOOOOOOOOOOOOOOOOOOOOOOOOOOOOOOOOOOOO | OOOOOOOOOOOOOOOOOOOOOOOOOOOOOOOOOOOOOOOOOOOOOOOOOOOOOOOOOOOOOOOOOOOOOOOOOOOOOOOOOOOOOOOOOO | OOOOOOOOOOOOOOOOOOOOOOOOOOOOOOOOOOOOOOOOOOOOOOOOOOOOOOOOOOOOOOOOOOOOOOOOOOOOOOOOOOOOOOOOOO | OOOOOOOOOOOOOOOOOOOOOOOOOOOOOOOOOOOOOOOOOOOOOOOOOOOOOOOOOOOOOOOOOOOOOOOOOOOOOOOOOOOOOOOOOO | OOOOOOOOOOOOOOOOOOOOOOOOOOOOOOOOOOOOOOOOOOOOOOOOOOOOOOOOOOOOOOOOOOOOOOOOOOOOOOOOOOOOOOOOOO | OOOOOOOOOOOOOOOOOOOOOOOOOOOOOOOOOOOOOOOOOOOOOOOOOOOOOOOOOOOOOOOOOOOOOOOOOOOOOOOOOOOOOOOOOO |  |
| TLA Parts Change |  |  |  |  |  |  |  |  |  |
| Item | Foxconn P/N | Qty | Part Description | Manufacturer Full Name | Manufacturer P/N | RoHS | Location | Remark |  |
| 1 | 7J-004-1582 | 2 | Label 1.25" (31.75mm) x 0.5"(6.35mm) | FOXCONN / EPD1 | 7J-004-1582 | G |  | In Old BOM |  |
| BOM Change List Date:Wed Sep 07 08:28:47 GMT+08:00 2016 |  |  |  |  |  |  |  |  |  |
| New BOM file : C:\<user>\ZAIUS-LBB-EVT1-X00-BOM-X01-20160907_Final.xls |  |  |  |  |  |  |  |  |  |
| Old BOM file : C:\<user>\ZAIUS-LBB-EVT-HW-EBOM-X00_20160829-X04_20160902.xls |  |  |  |  |  |  |  |  |  |
| ##### Add Parts |  |  |  |  |  |  |  |  |  |
| Item | Location | Qty | Foxconn P/N | Part Description | Manufacturer Full Name | Manufacturer P/N | RoHS | Sheet |  |
| ##### Remove Parts |  |  |  |  |  |  |  |  |  |
| Item | Location | Qty | Foxconn P/N | Part Description | Manufacturer Full Name | Manufacturer P/N | RoHS | Sheet |  |
| ##### Change Parts |  |  |  |  |  |  |  |  |  |
| Item | Location | Qty | Foxconn P/N | Part Description | Manufacturer Full Name | Manufacturer P/N | RoHS | Sheet | Remark |
| 1 | R2,R3,R4,R5 | 4 | 61015D800-017-G | RES,10KOhm,+/-5%,1W,G,SMD2512 | KOA SPEER ELECTRONICS, INC. | RK73BW3ATTE103J |  | PWA BOM | In New BOM |
|  |  |  | TBD-CRCW251210K0JNEG | RES,10KOhm,+/-5%,1W,G,SMD2512 | VISHAY ENTER TECHNO LOGY.INC | CRCW251210K0JNEG |  | PWA BOM | In New BOM |
|  | R2,R3,R4,R5 | 4 | 61015D800-017-G | RES,10KOhm,+/-5%,1W,G,SMD2512 | KOA SPEER ELECTRONICS, INC. | RK73BW3ATTE103J |  | PWA BOM | In Old BOM |
| 2 | R6,R8 | 2 | 61011J500-017-G | RES,270 Ohm,+/-1%,1/16W,G,SMD0402 | KOA SPEER ELECTRONICS, INC. | RK73H1ETTP2700F | N | PWA BOM | In New BOM |
|  |  |  | TBD-CRCW0402270RFKED | RES,270 Ohm,+/-1%,1/16W,G,SMD040 | VISHAY ENTER TECHNO LOGY.INC | CRCW0402270RFKED |  | PWA BOM | In New BOM |
|  | R6,R8 | 2 | 61011J500-017-G | RES,270 Ohm,+/-1%,1/16W,G,SMD0402 | KOA SPEER ELECTRONICS, INC. | RK73H1ETTP2700F | N | PWA BOM | In Old BOM |
| 3 | PCB | 1 | 0101DU700-000-G | PCB,Zaius-Lunch Box Board EVT-X00,OSP,Red,4L,7.8740*3.937,G | GOLD CIRCUIT ELECTRONICS LTD. | 0101DU700-000-G |  | PWA BOM | In New BOM |
|  | PCB | 1 | 0101DU700-000-G | PCB,Zaius-Lunch Box Board EVT-X00,OSP,Red,4L,7.8740*3.937,G | GCE | 0101DU700-000-G |  | PWA BOM | In Old BOM |
| 4 | C29,C33 | 2 | 620127H00-025-G | CAP,1uF,+/-10%,X7R,100V,G,SMD1812 | KEMET ELECTRONICS CORPORATION | C1812C105K1RACTU | Y | PWA BOM | In New BOM |
|  | C29,C33 | 2 | TBD-C1812C105K1RACTU | CAP,1uF,+/-10%,X7R,100V,G,SMD1812 | KEMET | C1812C105K1RACTU | Y | PWA BOM | In Old BOM |
| 5 | C30,C31,C32,C34,C35,C36 | 6 | 62012LE00-025-G | CAP,2.2uF,+/-10%,X7R,100V,G,SMD1812 | KEMET ELECTRONICS CORPORATION | C1812C225K1RACTU |  | PWA BOM | In New BOM |
|  |  |  | TBD-GRM43ER72A225KA01L | CAP,2.2uF,+/-10%,X7R,100V,G,SMD1812 | MURATA ELEC. NORTH AMERICA | GRM43ER72A225KA01L |  | PWA BOM | In New BOM |
|  | C30,C31,C32,C34,C35,C36 | 6 | TBD-C1812C225K1RACTU | CAP,2.2uF,+/-10%,X7R,100V,G,SMD1812 | KEMET | C1812C225K1RACTU |  | PWA BOM | In Old BOM |
| ##### Change Revision |  |  |  |  |  |  |  |  |  |
| Sheet | REV OF BOM | CUSTOMER | CUSTOMER P/N | PWA PN | PWA DESCRIPTION | PWA REV | DATE | Remark |  |
| PWA BOM | X01 | DELL |  | 10035WH00-600-G | Peripheral Board,G,Zaius-LBB | X00 | 9/7/16 | In New BOM |  |
| PWA BOM | X04 | DELL |  | 10035WH00-600-G | Peripheral Board,G,Zaius-LBB | X00 | 8/31/16 | In Old BOM |  |
| OOOOOOOOOOOOOOOOOOOOOOOOOOOOOOOOOOOOOOOOOOOOOOOOOOOOOOOOOOOOOOOOOOOOOOOOOOOOOOOOOOOOOOOOOO | OOOOOOOOOOOOOOOOOOOOOOOOOOOOOOOOOOOOOOOOOOOOOOOOOOOOOOOOOOOOOOOOOOOOOOOOOOOOOOOOOOOOOOOOOO | OOOOOOOOOOOOOOOOOOOOOOOOOOOOOOOOOOOOOOOOOOOOOOOOOOOOOOOOOOOOOOOOOOOOOOOOOOOOOOOOOOOOOOOOOO | OOOOOOOOOOOOOOOOOOOOOOOOOOOOOOOOOOOOOOOOOOOOOOOOOOOOOOOOOOOOOOOOOOOOOOOOOOOOOOOOOOOOOOOOOO | OOOOOOOOOOOOOOOOOOOOOOOOOOOOOOOOOOOOOOOOOOOOOOOOOOOOOOOOOOOOOOOOOOOOOOOOOOOOOOOOOOOOOOOOOO | OOOOOOOOOOOOOOOOOOOOOOOOOOOOOOOOOOOOOOOOOOOOOOOOOOOOOOOOOOOOOOOOOOOOOOOOOOOOOOOOOOOOOOOOOO | OOOOOOOOOOOOOOOOOOOOOOOOOOOOOOOOOOOOOOOOOOOOOOOOOOOOOOOOOOOOOOOOOOOOOOOOOOOOOOOOOOOOOOOOOO | OOOOOOOOOOOOOOOOOOOOOOOOOOOOOOOOOOOOOOOOOOOOOOOOOOOOOOOOOOOOOOOOOOOOOOOOOOOOOOOOOOOOOOOOOO | OOOOOOOOOOOOOOOOOOOOOOOOOOOOOOOOOOOOOOOOOOOOOOOOOOOOOOOOOOOOOOOOOOOOOOOOOOOOOOOOOOOOOOOOOO | OOOOOOOOOOOOOOOOOOOOOOOOOOOOOOOOOOOOOOOOOOOOOOOOOOOOOOOOOOOOOOOOOOOOOOOOOOOOOOOOOOOOOOOOOO |
| Second Source Change |  |  |  |  |  |  |  |  |  |
| Item | Location | Change Type | Foxconn P/N | Part Description | Manufacturer Full Name | Manufacturer P/N | RoHS | Sheet |  |
| 1 | R2,R3,R4,R5 |  | 61015D800-017-G | RES,10KOhm,+/-5%,1W,G,SMD2512 | KOA SPEER ELECTRONICS, INC. | RK73BW3ATTE103J |  | PWA BOM |  |
|  |  | ADD | TBD-CRCW251210K0JNEG | RES,10KOhm,+/-5%,1W,G,SMD2512 | VISHAY ENTER TECHNO LOGY.INC | CRCW251210K0JNEG |  | PWA BOM |  |
| 2 | R6,R8 |  | 61011J500-017-G | RES,270 Ohm,+/-1%,1/16W,G,SMD0402 | KOA SPEER ELECTRONICS, INC. | RK73H1ETTP2700F | N | PWA BOM |  |
|  |  | ADD | TBD-CRCW0402270RFKED | RES,270 Ohm,+/-1%,1/16W,G,SMD040 | VISHAY ENTER TECHNO LOGY.INC | CRCW0402270RFKED |  | PWA BOM |  |
| OOOOOOOOOOOOOOOOOOOOOOOOOOOOOOOOOOOOOOOOOOOOOOOOOOOOOOOOOOOOOOOOOOOOOOOOOOOOOOOOOOOOOOOOOO | OOOOOOOOOOOOOOOOOOOOOOOOOOOOOOOOOOOOOOOOOOOOOOOOOOOOOOOOOOOOOOOOOOOOOOOOOOOOOOOOOOOOOOOOOO | OOOOOOOOOOOOOOOOOOOOOOOOOOOOOOOOOOOOOOOOOOOOOOOOOOOOOOOOOOOOOOOOOOOOOOOOOOOOOOOOOOOOOOOOOO | OOOOOOOOOOOOOOOOOOOOOOOOOOOOOOOOOOOOOOOOOOOOOOOOOOOOOOOOOOOOOOOOOOOOOOOOOOOOOOOOOOOOOOOOOO | OOOOOOOOOOOOOOOOOOOOOOOOOOOOOOOOOOOOOOOOOOOOOOOOOOOOOOOOOOOOOOOOOOOOOOOOOOOOOOOOOOOOOOOOOO | OOOOOOOOOOOOOOOOOOOOOOOOOOOOOOOOOOOOOOOOOOOOOOOOOOOOOOOOOOOOOOOOOOOOOOOOOOOOOOOOOOOOOOOOOO | OOOOOOOOOOOOOOOOOOOOOOOOOOOOOOOOOOOOOOOOOOOOOOOOOOOOOOOOOOOOOOOOOOOOOOOOOOOOOOOOOOOOOOOOOO | OOOOOOOOOOOOOOOOOOOOOOOOOOOOOOOOOOOOOOOOOOOOOOOOOOOOOOOOOOOOOOOOOOOOOOOOOOOOOOOOOOOOOOOOOO | OOOOOOOOOOOOOOOOOOOOOOOOOOOOOOOOOOOOOOOOOOOOOOOOOOOOOOOOOOOOOOOOOOOOOOOOOOOOOOOOOOOOOOOOOO | OOOOOOOOOOOOOOOOOOOOOOOOOOOOOOOOOOOOOOOOOOOOOOOOOOOOOOOOOOOOOOOOOOOOOOOOOOOOOOOOOOOOOOOOOO |
| Master Materials Change |  |  |  |  |  |  |  |  |  |
| Item | Foxconn P/N | Orig._Usage | New_Usage | Part Description | Manufacturer Full Name | Manufacturer P/N | RoHS | Location | Sheet |
| 1 | 620127H00-025-G | 0 | 2 | CAP,1uF,+/-10%,X7R,100V,G,SMD1812 | KEMET ELECTRONICS CORPORATION | C1812C105K1RACTU | Y | (+)C29,C33 | PWA BOM |
| 2 | 62012LE00-025-G | 0 | 6 | CAP,2.2uF,+/-10%,X7R,100V,G,SMD1812 | KEMET ELECTRONICS CORPORATION | C1812C225K1RACTU |  | (+)C30,C31,C32,C34,C35,C36 | PWA BOM |
|  | TBD-GRM43ER72A225KA01L |  |  | CAP,2.2uF,+/-10%,X7R,100V,G,SMD1812 | MURATA ELEC. NORTH AMERICA | GRM43ER72A225KA01L |  |  | PWA BOM |
| 3 | TBD-C1812C105K1RACTU | 2 | 0 | CAP,1uF,+/-10%,X7R,100V,G,SMD1812 | KEMET | C1812C105K1RACTU | Y | (-)C29,C33 | PWA BOM |
| 4 | TBD-C1812C225K1RACTU | 6 | 0 | CAP,2.2uF,+/-10%,X7R,100V,G,SMD1812 | KEMET | C1812C225K1RACTU |  | (-)C30,C31,C32,C34,C35,C36 | PWA BOM |
| OOOOOOOOOOOOOOOOOOOOOOOOOOOOOOOOOOOOOOOOOOOOOOOOOOOOOOOOOOOOOOOOOOOOOOOOOOOOOOOOOOOOOOOOOO | OOOOOOOOOOOOOOOOOOOOOOOOOOOOOOOOOOOOOOOOOOOOOOOOOOOOOOOOOOOOOOOOOOOOOOOOOOOOOOOOOOOOOOOOOO | OOOOOOOOOOOOOOOOOOOOOOOOOOOOOOOOOOOOOOOOOOOOOOOOOOOOOOOOOOOOOOOOOOOOOOOOOOOOOOOOOOOOOOOOOO | OOOOOOOOOOOOOOOOOOOOOOOOOOOOOOOOOOOOOOOOOOOOOOOOOOOOOOOOOOOOOOOOOOOOOOOOOOOOOOOOOOOOOOOOOO | OOOOOOOOOOOOOOOOOOOOOOOOOOOOOOOOOOOOOOOOOOOOOOOOOOOOOOOOOOOOOOOOOOOOOOOOOOOOOOOOOOOOOOOOOO | OOOOOOOOOOOOOOOOOOOOOOOOOOOOOOOOOOOOOOOOOOOOOOOOOOOOOOOOOOOOOOOOOOOOOOOOOOOOOOOOOOOOOOOOOO | OOOOOOOOOOOOOOOOOOOOOOOOOOOOOOOOOOOOOOOOOOOOOOOOOOOOOOOOOOOOOOOOOOOOOOOOOOOOOOOOOOOOOOOOOO | OOOOOOOOOOOOOOOOOOOOOOOOOOOOOOOOOOOOOOOOOOOOOOOOOOOOOOOOOOOOOOOOOOOOOOOOOOOOOOOOOOOOOOOOOO | OOOOOOOOOOOOOOOOOOOOOOOOOOOOOOOOOOOOOOOOOOOOOOOOOOOOOOOOOOOOOOOOOOOOOOOOOOOOOOOOOOOOOOOOOO |  |
| TLA Parts Change |  |  |  |  |  |  |  |  |  |
| Item | Foxconn P/N | Qty | Part Description | Manufacturer Full Name | Manufacturer P/N | RoHS | Location | Remark |  |
| BOM Change List Date:Mon Oct 31 13:57:57 GMT+08:00 2016 |  |  |  |  |  |  |  |  |  |
| New BOM file : C:\<user>\ZAIUS-LBB-EVT2-X01-BOM-X02-20161031.xls |  |  |  |  |  |  |  |  |  |
| Old BOM file : C:\<user>\ZAIUS-LBB-EVT1-X00-BOM-X01-20160907_Final.xls |  |  |  |  |  |  |  |  |  |
| ##### Add Parts |  |  |  |  |  |  |  |  |  |
| Item | Location | Qty | Foxconn P/N | Part Description | Manufacturer Full Name | Manufacturer P/N | RoHS | Sheet |  |
| ##### Remove Parts |  |  |  |  |  |  |  |  |  |
| Item | Location | Qty | Foxconn P/N | Part Description | Manufacturer Full Name | Manufacturer P/N | RoHS | Sheet |  |
| ##### Change Parts |  |  |  |  |  |  |  |  |  |
| Item | Location | Qty | Foxconn P/N | Part Description | Manufacturer Full Name | Manufacturer P/N | RoHS | Sheet | Remark |
| 1 | R2,R3,R4,R5 | 4 | 61015D800-017-G | RES,10KOhm,+/-5%,1W,G,SMD2512 | KOA SPEER ELECTRONICS, INC. | RK73BW3ATTE103J |  | PWA BOM | In New BOM |
|  |  |  | 61015D800-029-G | RES,10KOhm,+/-5%,1W,G,SMD2512 | VISHAY ENTER TECHNO LOGY.INC | CRCW251210K0JNEG |  | PWA BOM | In New BOM |
|  | R2,R3,R4,R5 | 4 | 61015D800-017-G | RES,10KOhm,+/-5%,1W,G,SMD2512 | KOA SPEER ELECTRONICS, INC. | RK73BW3ATTE103J |  | PWA BOM | In Old BOM |
|  |  |  | TBD-CRCW251210K0JNEG | RES,10KOhm,+/-5%,1W,G,SMD2512 | VISHAY ENTER TECHNO LOGY.INC | CRCW251210K0JNEG |  | PWA BOM | In Old BOM |
| 2 | R6,R8 | 2 | 61011J500-017-G | RES,270 Ohm,+/-1%,1/16W,G,SMD0402 | KOA SPEER ELECTRONICS, INC. | RK73H1ETTP2700F | N | PWA BOM | In New BOM |
|  |  |  | 61011J500-029-G | RES,270 Ohm,+/-1%,1/16W,G,SMD040 | VISHAY ENTER TECHNO LOGY.INC | CRCW0402270RFKED |  | PWA BOM | In New BOM |
|  | R6,R8 | 2 | 61011J500-017-G | RES,270 Ohm,+/-1%,1/16W,G,SMD0402 | KOA SPEER ELECTRONICS, INC. | RK73H1ETTP2700F | N | PWA BOM | In Old BOM |
|  |  |  | TBD-CRCW0402270RFKED | RES,270 Ohm,+/-1%,1/16W,G,SMD040 | VISHAY ENTER TECHNO LOGY.INC | CRCW0402270RFKED |  | PWA BOM | In Old BOM |
| 3 | PCB | 1 | 0101E7M00-000-G | PCB,Zaius-Lunch Box Board EVT2-X01,OSP,Red,4L,7.874*3.937,G | GOLD CIRCUIT ELECTRONICS LTD. | 0101E7M00-000-G |  | PWA BOM | In New BOM |
|  | PCB | 1 | 0101DU700-000-G | PCB,Zaius-Lunch Box Board EVT-X00,OSP,Red,4L,7.8740*3.937,G | GOLD CIRCUIT ELECTRONICS LTD. | 0101DU700-000-G |  | PWA BOM | In Old BOM |
| 4 | C29,C33 | 2 | 62011DA00-015-G | CAP,1uF,+/-10%,X7R,100V,G,SMD1206 | MURATA ELEC. NORTH AMERICA | GRM31CR72A105K | Y | PWA BOM | In New BOM |
|  |  |  | 62011DA00-026-G | CAP,MLCC,1uF,+/-10%,X7R,100V,SMD1206,G | SAMSUNG | CL31B105KCHNNNE |  | PWA BOM | In New BOM |
|  |  |  | 62011DA00-023-G | CAP,MLCC,1uF,+/-10%,X7R,100V,SMD1206,G | TAIYO | HMK316B7105KL-T |  | PWA BOM | In New BOM |
|  | C29,C33 | 2 | 620127H00-025-G | CAP,1uF,+/-10%,X7R,100V,G,SMD1812 | KEMET ELECTRONICS CORPORATION | C1812C105K1RACTU | Y | PWA BOM | In Old BOM |
| 5 | C30,C31,C32,C34,C35,C36 | 6 | GRM31CR72A225KA73K | CAP,2.2uF,+/-10%,X7R,100V,G,SMD1206 | MURATA ELEC. NORTH AMERICA | GRM31CR72A225KA73K |  | PWA BOM | In New BOM |
|  | C30,C31,C32,C34,C35,C36 | 6 | 62012LE00-025-G | CAP,2.2uF,+/-10%,X7R,100V,G,SMD1812 | KEMET ELECTRONICS CORPORATION | C1812C225K1RACTU |  | PWA BOM | In Old BOM |
|  |  |  | TBD-GRM43ER72A225KA01L | CAP,2.2uF,+/-10%,X7R,100V,G,SMD1812 | MURATA ELEC. NORTH AMERICA | GRM43ER72A225KA01L |  | PWA BOM | In Old BOM |
| ##### Change Revision |  |  |  |  |  |  |  |  |  |
| Sheet | REV OF BOM | CUSTOMER | CUSTOMER P/N | PWA PN | PWA DESCRIPTION | PWA REV | DATE | Remark |  |
| PWA BOM | X02 | DELL |  |  | Peripheral Board,G,Zaius-LBB |  |  | In New BOM |  |
| PWA BOM | X01 | DELL |  | 10035WH00-600-G | Peripheral Board,G,Zaius-LBB | X00 | 9/7/16 | In Old BOM |  |
| OOOOOOOOOOOOOOOOOOOOOOOOOOOOOOOOOOOOOOOOOOOOOOOOOOOOOOOOOOOOOOOOOOOOOOOOOOOOOOOOOOOOOOOOOO | OOOOOOOOOOOOOOOOOOOOOOOOOOOOOOOOOOOOOOOOOOOOOOOOOOOOOOOOOOOOOOOOOOOOOOOOOOOOOOOOOOOOOOOOOO | OOOOOOOOOOOOOOOOOOOOOOOOOOOOOOOOOOOOOOOOOOOOOOOOOOOOOOOOOOOOOOOOOOOOOOOOOOOOOOOOOOOOOOOOOO | OOOOOOOOOOOOOOOOOOOOOOOOOOOOOOOOOOOOOOOOOOOOOOOOOOOOOOOOOOOOOOOOOOOOOOOOOOOOOOOOOOOOOOOOOO | OOOOOOOOOOOOOOOOOOOOOOOOOOOOOOOOOOOOOOOOOOOOOOOOOOOOOOOOOOOOOOOOOOOOOOOOOOOOOOOOOOOOOOOOOO | OOOOOOOOOOOOOOOOOOOOOOOOOOOOOOOOOOOOOOOOOOOOOOOOOOOOOOOOOOOOOOOOOOOOOOOOOOOOOOOOOOOOOOOOOO | OOOOOOOOOOOOOOOOOOOOOOOOOOOOOOOOOOOOOOOOOOOOOOOOOOOOOOOOOOOOOOOOOOOOOOOOOOOOOOOOOOOOOOOOOO | OOOOOOOOOOOOOOOOOOOOOOOOOOOOOOOOOOOOOOOOOOOOOOOOOOOOOOOOOOOOOOOOOOOOOOOOOOOOOOOOOOOOOOOOOO | OOOOOOOOOOOOOOOOOOOOOOOOOOOOOOOOOOOOOOOOOOOOOOOOOOOOOOOOOOOOOOOOOOOOOOOOOOOOOOOOOOOOOOOOOO | OOOOOOOOOOOOOOOOOOOOOOOOOOOOOOOOOOOOOOOOOOOOOOOOOOOOOOOOOOOOOOOOOOOOOOOOOOOOOOOOOOOOOOOOOO |
| Second Source Change |  |  |  |  |  |  |  |  |  |
| Item | Location | Change Type | Foxconn P/N | Part Description | Manufacturer Full Name | Manufacturer P/N | RoHS | Sheet |  |
| 1 | R2,R3,R4,R5 |  | 61015D800-017-G | RES,10KOhm,+/-5%,1W,G,SMD2512 | KOA SPEER ELECTRONICS, INC. | RK73BW3ATTE103J |  | PWA BOM |  |
|  |  | ADD | 61015D800-029-G | RES,10KOhm,+/-5%,1W,G,SMD2512 | VISHAY ENTER TECHNO LOGY.INC | CRCW251210K0JNEG |  | PWA BOM |  |
|  |  | Delete | TBD-CRCW251210K0JNEG | RES,10KOhm,+/-5%,1W,G,SMD2512 | VISHAY ENTER TECHNO LOGY.INC | CRCW251210K0JNEG |  | PWA BOM |  |
| 2 | R6,R8 |  | 61011J500-017-G | RES,270 Ohm,+/-1%,1/16W,G,SMD0402 | KOA SPEER ELECTRONICS, INC. | RK73H1ETTP2700F | N | PWA BOM |  |
|  |  | ADD | 61011J500-029-G | RES,270 Ohm,+/-1%,1/16W,G,SMD040 | VISHAY ENTER TECHNO LOGY.INC | CRCW0402270RFKED |  | PWA BOM |  |
|  |  | Delete | TBD-CRCW0402270RFKED | RES,270 Ohm,+/-1%,1/16W,G,SMD040 | VISHAY ENTER TECHNO LOGY.INC | CRCW0402270RFKED |  | PWA BOM |  |
| OOOOOOOOOOOOOOOOOOOOOOOOOOOOOOOOOOOOOOOOOOOOOOOOOOOOOOOOOOOOOOOOOOOOOOOOOOOOOOOOOOOOOOOOOO | OOOOOOOOOOOOOOOOOOOOOOOOOOOOOOOOOOOOOOOOOOOOOOOOOOOOOOOOOOOOOOOOOOOOOOOOOOOOOOOOOOOOOOOOOO | OOOOOOOOOOOOOOOOOOOOOOOOOOOOOOOOOOOOOOOOOOOOOOOOOOOOOOOOOOOOOOOOOOOOOOOOOOOOOOOOOOOOOOOOOO | OOOOOOOOOOOOOOOOOOOOOOOOOOOOOOOOOOOOOOOOOOOOOOOOOOOOOOOOOOOOOOOOOOOOOOOOOOOOOOOOOOOOOOOOOO | OOOOOOOOOOOOOOOOOOOOOOOOOOOOOOOOOOOOOOOOOOOOOOOOOOOOOOOOOOOOOOOOOOOOOOOOOOOOOOOOOOOOOOOOOO | OOOOOOOOOOOOOOOOOOOOOOOOOOOOOOOOOOOOOOOOOOOOOOOOOOOOOOOOOOOOOOOOOOOOOOOOOOOOOOOOOOOOOOOOOO | OOOOOOOOOOOOOOOOOOOOOOOOOOOOOOOOOOOOOOOOOOOOOOOOOOOOOOOOOOOOOOOOOOOOOOOOOOOOOOOOOOOOOOOOOO | OOOOOOOOOOOOOOOOOOOOOOOOOOOOOOOOOOOOOOOOOOOOOOOOOOOOOOOOOOOOOOOOOOOOOOOOOOOOOOOOOOOOOOOOOO | OOOOOOOOOOOOOOOOOOOOOOOOOOOOOOOOOOOOOOOOOOOOOOOOOOOOOOOOOOOOOOOOOOOOOOOOOOOOOOOOOOOOOOOOOO | OOOOOOOOOOOOOOOOOOOOOOOOOOOOOOOOOOOOOOOOOOOOOOOOOOOOOOOOOOOOOOOOOOOOOOOOOOOOOOOOOOOOOOOOOO |
| Master Materials Change |  |  |  |  |  |  |  |  |  |
| Item | Foxconn P/N | Orig._Usage | New_Usage | Part Description | Manufacturer Full Name | Manufacturer P/N | RoHS | Location | Sheet |
| 1 | 0101E7M00-000-G | 0 | 1 | PCB,Zaius-Lunch Box Board EVT2-X01,OSP,Red,4L,7.874*3.937,G | GOLD CIRCUIT ELECTRONICS LTD. | 0101E7M00-000-G |  | (+)PCB | PWA BOM |
| 2 | 62011DA00-015-G | 0 | 2 | CAP,1uF,+/-10%,X7R,100V,G,SMD1206 | MURATA ELEC. NORTH AMERICA | GRM31CR72A105K | Y | (+)C29,C33 | PWA BOM |
|  | 62011DA00-026-G |  |  | CAP,MLCC,1uF,+/-10%,X7R,100V,SMD1206,G | SAMSUNG | CL31B105KCHNNNE |  |  | PWA BOM |
|  | 62011DA00-023-G |  |  | CAP,MLCC,1uF,+/-10%,X7R,100V,SMD1206,G | TAIYO | HMK316B7105KL-T |  |  | PWA BOM |
| 3 | GRM31CR72A225KA73K | 0 | 6 | CAP,2.2uF,+/-10%,X7R,100V,G,SMD1206 | MURATA ELEC. NORTH AMERICA | GRM31CR72A225KA73K |  | (+)C30,C31,C32,C34,C35,C36 | PWA BOM |
| 4 | 0101DU700-000-G | 1 | 0 | PCB,Zaius-Lunch Box Board EVT-X00,OSP,Red,4L,7.8740*3.937,G | GOLD CIRCUIT ELECTRONICS LTD. | 0101DU700-000-G |  | (-)PCB | PWA BOM |
| 5 | 620127H00-025-G | 2 | 0 | CAP,1uF,+/-10%,X7R,100V,G,SMD1812 | KEMET ELECTRONICS CORPORATION | C1812C105K1RACTU | Y | (-)C29,C33 | PWA BOM |
| 6 | 62012LE00-025-G | 6 | 0 | CAP,2.2uF,+/-10%,X7R,100V,G,SMD1812 | KEMET ELECTRONICS CORPORATION | C1812C225K1RACTU |  | (-)C30,C31,C32,C34,C35,C36 | PWA BOM |
|  | TBD-GRM43ER72A225KA01L |  |  | CAP,2.2uF,+/-10%,X7R,100V,G,SMD1812 | MURATA ELEC. NORTH AMERICA | GRM43ER72A225KA01L |  |  | PWA BOM |
| OOOOOOOOOOOOOOOOOOOOOOOOOOOOOOOOOOOOOOOOOOOOOOOOOOOOOOOOOOOOOOOOOOOOOOOOOOOOOOOOOOOOOOOOOO | OOOOOOOOOOOOOOOOOOOOOOOOOOOOOOOOOOOOOOOOOOOOOOOOOOOOOOOOOOOOOOOOOOOOOOOOOOOOOOOOOOOOOOOOOO | OOOOOOOOOOOOOOOOOOOOOOOOOOOOOOOOOOOOOOOOOOOOOOOOOOOOOOOOOOOOOOOOOOOOOOOOOOOOOOOOOOOOOOOOOO | OOOOOOOOOOOOOOOOOOOOOOOOOOOOOOOOOOOOOOOOOOOOOOOOOOOOOOOOOOOOOOOOOOOOOOOOOOOOOOOOOOOOOOOOOO | OOOOOOOOOOOOOOOOOOOOOOOOOOOOOOOOOOOOOOOOOOOOOOOOOOOOOOOOOOOOOOOOOOOOOOOOOOOOOOOOOOOOOOOOOO | OOOOOOOOOOOOOOOOOOOOOOOOOOOOOOOOOOOOOOOOOOOOOOOOOOOOOOOOOOOOOOOOOOOOOOOOOOOOOOOOOOOOOOOOOO | OOOOOOOOOOOOOOOOOOOOOOOOOOOOOOOOOOOOOOOOOOOOOOOOOOOOOOOOOOOOOOOOOOOOOOOOOOOOOOOOOOOOOOOOOO | OOOOOOOOOOOOOOOOOOOOOOOOOOOOOOOOOOOOOOOOOOOOOOOOOOOOOOOOOOOOOOOOOOOOOOOOOOOOOOOOOOOOOOOOOO | OOOOOOOOOOOOOOOOOOOOOOOOOOOOOOOOOOOOOOOOOOOOOOOOOOOOOOOOOOOOOOOOOOOOOOOOOOOOOOOOOOOOOOOOOO |  |
| TLA Parts Change |  |  |  |  |  |  |  |  |  |
| Item | Foxconn P/N | Qty | Part Description | Manufacturer Full Name | Manufacturer P/N | RoHS | Location | Remark |  |
| BOM Change List Date:Wed Nov 16 11:55:29 GMT+08:00 2016 |  |  |  |  |  |  |  |  |  |
| New BOM file : ZAIUS-LBB-EVT2-X01-BOM-X03-20161116.xls |  |  |  |  |  |  |  |  |  |
| Old BOM file : ZAIUS-LBB-EVT2-X01-BOM-X02-20161031.xls |  |  |  |  |  |  |  |  |  |
| ##### Add Parts |  |  |  |  |  |  |  |  |  |
| Item | Location | Qty | Foxconn P/N | Part Description | Manufacturer Full Name | Manufacturer P/N | RoHS | Sheet |  |
| ##### Remove Parts |  |  |  |  |  |  |  |  |  |
| Item | Location | Qty | Foxconn P/N | Part Description | Manufacturer Full Name | Manufacturer P/N | RoHS | Sheet |  |
| ##### Change Parts |  |  |  |  |  |  |  |  |  |
| Item | Location | Qty | Foxconn P/N | Part Description | Manufacturer Full Name | Manufacturer P/N | RoHS | Sheet | Remark |
| 1 | C29,C33 | 2 | 62011DA02-015-G | CAP,1uF,+/-10%,X7R,100V,G,SMD1206 | MURATA ELEC. NORTH AMERICA | GRM31CR72A105KA01K | Y | PWA BOM | In New BOM |
|  |  |  | 62011DA00-026-G | CAP,MLCC,1uF,+/-10%,X7R,100V,SMD1206,G | SAMSUNG | CL31B105KCHNNNE |  | PWA BOM | In New BOM |
|  |  |  | 62011DA00-023-G | CAP,MLCC,1uF,+/-10%,X7R,100V,SMD1206,G | TAIYO | HMK316B7105KL-T |  | PWA BOM | In New BOM |
|  | C29,C33 | 2 | 62011DA00-015-G | CAP,1uF,+/-10%,X7R,100V,G,SMD1206 | MURATA ELEC. NORTH AMERICA | GRM31CR72A105K | Y | PWA BOM | In Old BOM |
|  |  |  | 62011DA00-026-G | CAP,MLCC,1uF,+/-10%,X7R,100V,SMD1206,G | SAMSUNG | CL31B105KCHNNNE |  | PWA BOM | In Old BOM |
|  |  |  | 62011DA00-023-G | CAP,MLCC,1uF,+/-10%,X7R,100V,SMD1206,G | TAIYO | HMK316B7105KL-T |  | PWA BOM | In Old BOM |
| ##### Change Revision |  |  |  |  |  |  |  |  |  |
| Sheet | REV OF BOM | CUSTOMER | CUSTOMER P/N | PWA PN | PWA DESCRIPTION | PWA REV | DATE | Remark |  |
| OOOOOOOOOOOOOOOOOOOOOOOOOOOOOOOOOOOOOOOOOOOOOOOOOOOOOOOOOOOOOOOOOOOOOOOOOOOOOOOOOOOOOOOOOO | OOOOOOOOOOOOOOOOOOOOOOOOOOOOOOOOOOOOOOOOOOOOOOOOOOOOOOOOOOOOOOOOOOOOOOOOOOOOOOOOOOOOOOOOOO | OOOOOOOOOOOOOOOOOOOOOOOOOOOOOOOOOOOOOOOOOOOOOOOOOOOOOOOOOOOOOOOOOOOOOOOOOOOOOOOOOOOOOOOOOO | OOOOOOOOOOOOOOOOOOOOOOOOOOOOOOOOOOOOOOOOOOOOOOOOOOOOOOOOOOOOOOOOOOOOOOOOOOOOOOOOOOOOOOOOOO | OOOOOOOOOOOOOOOOOOOOOOOOOOOOOOOOOOOOOOOOOOOOOOOOOOOOOOOOOOOOOOOOOOOOOOOOOOOOOOOOOOOOOOOOOO | OOOOOOOOOOOOOOOOOOOOOOOOOOOOOOOOOOOOOOOOOOOOOOOOOOOOOOOOOOOOOOOOOOOOOOOOOOOOOOOOOOOOOOOOOO | OOOOOOOOOOOOOOOOOOOOOOOOOOOOOOOOOOOOOOOOOOOOOOOOOOOOOOOOOOOOOOOOOOOOOOOOOOOOOOOOOOOOOOOOOO | OOOOOOOOOOOOOOOOOOOOOOOOOOOOOOOOOOOOOOOOOOOOOOOOOOOOOOOOOOOOOOOOOOOOOOOOOOOOOOOOOOOOOOOOOO | OOOOOOOOOOOOOOOOOOOOOOOOOOOOOOOOOOOOOOOOOOOOOOOOOOOOOOOOOOOOOOOOOOOOOOOOOOOOOOOOOOOOOOOOOO | OOOOOOOOOOOOOOOOOOOOOOOOOOOOOOOOOOOOOOOOOOOOOOOOOOOOOOOOOOOOOOOOOOOOOOOOOOOOOOOOOOOOOOOOOO |
| Second Source Change |  |  |  |  |  |  |  |  |  |
| Item | Location | Change Type | Foxconn P/N | Part Description | Manufacturer Full Name | Manufacturer P/N | RoHS | Sheet |  |
| OOOOOOOOOOOOOOOOOOOOOOOOOOOOOOOOOOOOOOOOOOOOOOOOOOOOOOOOOOOOOOOOOOOOOOOOOOOOOOOOOOOOOOOOOO | OOOOOOOOOOOOOOOOOOOOOOOOOOOOOOOOOOOOOOOOOOOOOOOOOOOOOOOOOOOOOOOOOOOOOOOOOOOOOOOOOOOOOOOOOO | OOOOOOOOOOOOOOOOOOOOOOOOOOOOOOOOOOOOOOOOOOOOOOOOOOOOOOOOOOOOOOOOOOOOOOOOOOOOOOOOOOOOOOOOOO | OOOOOOOOOOOOOOOOOOOOOOOOOOOOOOOOOOOOOOOOOOOOOOOOOOOOOOOOOOOOOOOOOOOOOOOOOOOOOOOOOOOOOOOOOO | OOOOOOOOOOOOOOOOOOOOOOOOOOOOOOOOOOOOOOOOOOOOOOOOOOOOOOOOOOOOOOOOOOOOOOOOOOOOOOOOOOOOOOOOOO | OOOOOOOOOOOOOOOOOOOOOOOOOOOOOOOOOOOOOOOOOOOOOOOOOOOOOOOOOOOOOOOOOOOOOOOOOOOOOOOOOOOOOOOOOO | OOOOOOOOOOOOOOOOOOOOOOOOOOOOOOOOOOOOOOOOOOOOOOOOOOOOOOOOOOOOOOOOOOOOOOOOOOOOOOOOOOOOOOOOOO | OOOOOOOOOOOOOOOOOOOOOOOOOOOOOOOOOOOOOOOOOOOOOOOOOOOOOOOOOOOOOOOOOOOOOOOOOOOOOOOOOOOOOOOOOO | OOOOOOOOOOOOOOOOOOOOOOOOOOOOOOOOOOOOOOOOOOOOOOOOOOOOOOOOOOOOOOOOOOOOOOOOOOOOOOOOOOOOOOOOOO | OOOOOOOOOOOOOOOOOOOOOOOOOOOOOOOOOOOOOOOOOOOOOOOOOOOOOOOOOOOOOOOOOOOOOOOOOOOOOOOOOOOOOOOOOO |
| Master Materials Change |  |  |  |  |  |  |  |  |  |
| Item | Foxconn P/N | Orig._Usage | New_Usage | Part Description | Manufacturer Full Name | Manufacturer P/N | RoHS | Location | Sheet |
| 1 | 62011DA02-015-G | 0 | 2 | CAP,1uF,+/-10%,X7R,100V,G,SMD1206 | MURATA ELEC. NORTH AMERICA | GRM31CR72A105KA01K | Y | (+)C29,C33 | PWA BOM |
|  | 62011DA00-026-G |  |  | CAP,MLCC,1uF,+/-10%,X7R,100V,SMD1206,G | SAMSUNG | CL31B105KCHNNNE |  |  | PWA BOM |
|  | 62011DA00-023-G |  |  | CAP,MLCC,1uF,+/-10%,X7R,100V,SMD1206,G | TAIYO | HMK316B7105KL-T |  |  | PWA BOM |
| 2 | 62011DA00-015-G | 2 | 0 | CAP,1uF,+/-10%,X7R,100V,G,SMD1206 | MURATA ELEC. NORTH AMERICA | GRM31CR72A105K | Y | (-)C29,C33 | PWA BOM |
|  | 62011DA00-026-G |  |  | CAP,MLCC,1uF,+/-10%,X7R,100V,SMD1206,G | SAMSUNG | CL31B105KCHNNNE |  |  | PWA BOM |
|  | 62011DA00-023-G |  |  | CAP,MLCC,1uF,+/-10%,X7R,100V,SMD1206,G | TAIYO | HMK316B7105KL-T |  |  | PWA BOM |
| OOOOOOOOOOOOOOOOOOOOOOOOOOOOOOOOOOOOOOOOOOOOOOOOOOOOOOOOOOOOOOOOOOOOOOOOOOOOOOOOOOOOOOOOOO | OOOOOOOOOOOOOOOOOOOOOOOOOOOOOOOOOOOOOOOOOOOOOOOOOOOOOOOOOOOOOOOOOOOOOOOOOOOOOOOOOOOOOOOOOO | OOOOOOOOOOOOOOOOOOOOOOOOOOOOOOOOOOOOOOOOOOOOOOOOOOOOOOOOOOOOOOOOOOOOOOOOOOOOOOOOOOOOOOOOOO | OOOOOOOOOOOOOOOOOOOOOOOOOOOOOOOOOOOOOOOOOOOOOOOOOOOOOOOOOOOOOOOOOOOOOOOOOOOOOOOOOOOOOOOOOO | OOOOOOOOOOOOOOOOOOOOOOOOOOOOOOOOOOOOOOOOOOOOOOOOOOOOOOOOOOOOOOOOOOOOOOOOOOOOOOOOOOOOOOOOOO | OOOOOOOOOOOOOOOOOOOOOOOOOOOOOOOOOOOOOOOOOOOOOOOOOOOOOOOOOOOOOOOOOOOOOOOOOOOOOOOOOOOOOOOOOO | OOOOOOOOOOOOOOOOOOOOOOOOOOOOOOOOOOOOOOOOOOOOOOOOOOOOOOOOOOOOOOOOOOOOOOOOOOOOOOOOOOOOOOOOOO | OOOOOOOOOOOOOOOOOOOOOOOOOOOOOOOOOOOOOOOOOOOOOOOOOOOOOOOOOOOOOOOOOOOOOOOOOOOOOOOOOOOOOOOOOO | OOOOOOOOOOOOOOOOOOOOOOOOOOOOOOOOOOOOOOOOOOOOOOOOOOOOOOOOOOOOOOOOOOOOOOOOOOOOOOOOOOOOOOOOOO |  |
| TLA Parts Change |  |  |  |  |  |  |  |  |  |
| Item | Foxconn P/N | Qty | Part Description | Manufacturer Full Name | Manufacturer P/N | RoHS | Location | Remark |  |
